# BASEBOARD_FAB2 (Tioga Pass) — schematic netlist excerpt (pin names and nets, part order shuffled) for the footprints in the layout excerpt that follows; sources: Cadence DE-HDL packaged netlist, KiCad conversion of Wiwynn_Tioga_Pass_MB.brd

R8C16  RES  2.0K 1% CHIP  pkg 0402  page 159 : A = P3V3_STBY ; B = SMB_HOST_STBY_LVC3_SDA_R
C2D27  CAP_A  22.0UF 4V 20% X6S  pkg 0603V  page 76 : A = PVCCIN_CPU1 ; B = GND
C2D43  CAP_A  22.0UF 4V 20% X6S  pkg 0603V  page 225 : A = PVDDQ_GHJ ; B = GND

(kicad_pcb
	(version 20260206)
	(generator "pcbnew")
	(generator_version "10.0")
	(general
		(thickness 1.6)
		(legacy_teardrops no)
	)
	(paper "A4")
	(title_block
		(title "Wiwynn_Tioga_Pass_MB.brd")
		(comment 1 "Tioga Pass / footprints 1037-1039 of 4770")
	)
	(layers
		(0 "F.Cu" signal "TOP")
		(4 "In1.Cu" signal "L2GND")
		(6 "In2.Cu" signal "L3")
		(8 "In3.Cu" signal "L4GND")
		(10 "In4.Cu" signal "L5")
		(12 "In5.Cu" signal "L6GND")
		(14 "In6.Cu" signal "L7VCC")
		(16 "In7.Cu" signal "L8VCC")
		(18 "In8.Cu" signal "L9GND")
		(20 "In9.Cu" signal "L10")
		(22 "In10.Cu" signal "L11GND")
		(24 "In11.Cu" signal "L12")
		(26 "In12.Cu" signal "L13GND")
		(2 "B.Cu" signal "BOTTOM")
		(9 "F.Adhes" user "F.Adhesive")
		(11 "B.Adhes" user "B.Adhesive")
		(13 "F.Paste" user "Package Geometry/Pastemask Top")
		(15 "B.Paste" user "Package Geometry/Pastemask Bottom")
		(5 "F.SilkS" user "Ref Des/Silkscreen Top")
		(7 "B.SilkS" user "Ref Des/Silkscreen Bottom")
		(1 "F.Mask" user "Board Geometry/Soldermask Top")
		(3 "B.Mask" user "Board Geometry/Soldermask Bottom")
		(17 "Dwgs.User" user "User.Drawings")
		(19 "Cmts.User" user "User.Comments")
		(21 "Eco1.User" user "User.Eco1")
		(23 "Eco2.User" user "User.Eco2")
		(25 "Edge.Cuts" user "Board Geometry/Outline")
		(27 "Margin" user)
		(31 "F.CrtYd" user "Package Geometry/Place Bound Top")
		(29 "B.CrtYd" user "Package Geometry/Place Bound Bottom")
		(35 "F.Fab" user "Ref Des/Assembly Top")
		(33 "B.Fab" user "Ref Des/Assembly Bottom")
	)
	(footprint ""
		(layer "F.Cu")
		(at 400.489674 -33.50514)
		(property "Reference" "R8C16"
			(at 0 0 0)
			(layer "F.SilkS")
			(hide yes)
			(effects
				(font
					(size 1.27 1.27)
				)
			)
		)
		(property "Value" ""
			(at 0 0 0)
			(layer "F.Fab")
			(effects
				(font
					(size 1.27 1.27)
				)
			)
		)
		(duplicate_pad_numbers_are_jumpers no)
		(fp_poly
			(pts
				(xy -0.2794 -0.1016) (xy 0.2794 -0.1016) (xy 0.2794 0.9906) (xy -0.2794 0.9906)
			)
			(stroke
				(width 0)
				(type default)
			)
			(fill no)
			(layer "F.CrtYd")
		)
		(fp_line
			(start -0.2794 -0.1016)
			(end -0.2794 0.9906)
			(stroke
				(width 0.1)
				(type default)
			)
			(layer "F.Fab")
		)
		(fp_line
			(start -0.2794 0.9906)
			(end 0.2794 0.9906)
			(stroke
				(width 0.1)
				(type default)
			)
			(layer "F.Fab")
		)
		(fp_line
			(start 0.2794 -0.1016)
			(end -0.2794 -0.1016)
			(stroke
				(width 0.1)
				(type default)
			)
			(layer "F.Fab")
		)
		(fp_line
			(start 0.2794 0.9906)
			(end 0.2794 -0.1016)
			(stroke
				(width 0.1)
				(type default)
			)
			(layer "F.Fab")
		)
		(pad "1" smd rect
			(at 0 0)
			(size 0.508 0.508)
			(layers "F.Cu" "F.Mask" "F.Paste")
			(net "P3V3_STBY")
		)
		(pad "2" smd rect
			(at 0 0.889)
			(size 0.508 0.508)
			(layers "F.Cu" "F.Mask" "F.Paste")
			(net "SMB_HOST_STBY_LVC3_SDA_R")
		)
		(zone
			(layer "F.Cu")
			(hatch none 0.5)
			(connect_pads
				(clearance 0)
			)
			(min_thickness 0.25)
			(keepout
				(tracks allowed)
				(vias not_allowed)
				(pads allowed)
				(copperpour not_allowed)
				(footprints allowed)
			)
			(placement
				(enabled no)
				(sheetname "")
			)
			(fill
				(thermal_gap 0.5)
				(thermal_bridge_width 0.5)
				(island_removal_mode 0)
			)
			(polygon
				(pts
					(xy 400.235674 -33.25114) (xy 400.743674 -33.25114) (xy 400.743674 -32.87014) (xy 400.235674 -32.87014)
				)
			)
		)
		(zone
			(layer "F.Cu")
			(hatch none 0.5)
			(connect_pads
				(clearance 0)
			)
			(min_thickness 0.25)
			(keepout
				(tracks not_allowed)
				(vias allowed)
				(pads allowed)
				(copperpour not_allowed)
				(footprints allowed)
			)
			(placement
				(enabled no)
				(sheetname "")
			)
			(fill
				(thermal_gap 0.5)
				(thermal_bridge_width 0.5)
				(island_removal_mode 0)
			)
			(polygon
				(pts
					(xy 400.235674 -32.87014) (xy 400.743674 -32.87014) (xy 400.743674 -33.25114) (xy 400.235674 -33.25114)
				)
			)
		)
	)
	(footprint ""
		(layer "F.Cu")
		(at 103.16464 -77.636116)
		(property "Reference" "C2D27"
			(at 0 0 0)
			(layer "F.SilkS")
			(hide yes)
			(effects
				(font
					(size 1.27 1.27)
				)
			)
		)
		(property "Value" ""
			(at 0 0 0)
			(layer "F.Fab")
			(effects
				(font
					(size 1.27 1.27)
				)
			)
		)
		(duplicate_pad_numbers_are_jumpers no)
		(fp_poly
			(pts
				(xy -0.4953 -0.2032) (xy 0.4953 -0.2032) (xy 0.4953 1.6002) (xy -0.4953 1.6002)
			)
			(stroke
				(width 0)
				(type default)
			)
			(fill no)
			(layer "F.CrtYd")
		)
		(fp_line
			(start -0.4953 -0.2032)
			(end 0.4953 -0.2032)
			(stroke
				(width 0.1)
				(type default)
			)
			(layer "F.Fab")
		)
		(fp_line
			(start -0.4953 1.6002)
			(end -0.4953 -0.2032)
			(stroke
				(width 0.1)
				(type default)
			)
			(layer "F.Fab")
		)
		(fp_line
			(start 0.4953 -0.2032)
			(end 0.4953 1.6002)
			(stroke
				(width 0.1)
				(type default)
			)
			(layer "F.Fab")
		)
		(fp_line
			(start 0.4953 1.6002)
			(end -0.4953 1.6002)
			(stroke
				(width 0.1)
				(type default)
			)
			(layer "F.Fab")
		)
		(pad "1" smd rect
			(at 0 0)
			(size 0.762 0.889)
			(layers "F.Cu" "F.Mask" "F.Paste")
			(net "PVCCIN_CPU1")
		)
		(pad "2" smd rect
			(at 0 1.397)
			(size 0.762 0.889)
			(layers "F.Cu" "F.Mask" "F.Paste")
			(net "GND")
		)
		(zone
			(layer "F.Cu")
			(hatch none 0.5)
			(connect_pads
				(clearance 0)
			)
			(min_thickness 0.25)
			(keepout
				(tracks not_allowed)
				(vias allowed)
				(pads allowed)
				(copperpour not_allowed)
				(footprints allowed)
			)
			(placement
				(enabled no)
				(sheetname "")
			)
			(fill
				(thermal_gap 0.5)
				(thermal_bridge_width 0.5)
				(island_removal_mode 0)
			)
			(polygon
				(pts
					(xy 102.78364 -77.191616) (xy 103.54564 -77.191616) (xy 103.54564 -76.683616) (xy 102.78364 -76.683616)
				)
			)
		)
	)
	(footprint ""
		(layer "F.Cu")
		(at 100.903024 -68.412614 180)
		(property "Reference" "C2D43"
			(at 0 0 180)
			(layer "F.SilkS")
			(hide yes)
			(effects
				(font
					(size 1.27 1.27)
				)
			)
		)
		(property "Value" ""
			(at 0 0 180)
			(layer "F.Fab")
			(effects
				(font
					(size 1.27 1.27)
				)
			)
		)
		(duplicate_pad_numbers_are_jumpers no)
		(fp_poly
			(pts
				(xy -0.4953 -0.2032) (xy 0.4953 -0.2032) (xy 0.4953 1.6002) (xy -0.4953 1.6002)
			)
			(stroke
				(width 0)
				(type default)
			)
			(fill no)
			(layer "F.CrtYd")
		)
		(fp_line
			(start 0.4953 1.6002)
			(end -0.4953 1.6002)
			(stroke
				(width 0.1)
				(type default)
			)
			(layer "F.Fab")
		)
		(fp_line
			(start 0.4953 -0.2032)
			(end 0.4953 1.6002)
			(stroke
				(width 0.1)
				(type default)
			)
			(layer "F.Fab")
		)
		(fp_line
			(start -0.4953 1.6002)
			(end -0.4953 -0.2032)
			(stroke
				(width 0.1)
				(type default)
			)
			(layer "F.Fab")
		)
		(fp_line
			(start -0.4953 -0.2032)
			(end 0.4953 -0.2032)
			(stroke
				(width 0.1)
				(type default)
			)
			(layer "F.Fab")
		)
		(pad "1" smd rect
			(at 0 0 180)
			(size 0.762 0.889)
			(layers "F.Cu" "F.Mask" "F.Paste")
			(net "PVDDQ_GHJ")
		)
		(pad "2" smd rect
			(at 0 1.397 180)
			(size 0.762 0.889)
			(layers "F.Cu" "F.Mask" "F.Paste")
			(net "GND")
		)
		(zone
			(layer "F.Cu")
			(hatch none 0.5)
			(connect_pads
				(clearance 0)
			)
			(min_thickness 0.25)
			(keepout
				(tracks not_allowed)
				(vias allowed)
				(pads allowed)
				(copperpour not_allowed)
				(footprints allowed)
			)
			(placement
				(enabled no)
				(sheetname "")
			)
			(fill
				(thermal_gap 0.5)
				(thermal_bridge_width 0.5)
				(island_removal_mode 0)
			)
			(polygon
				(pts
					(xy 101.284024 -68.857114) (xy 100.522024 -68.857114) (xy 100.522024 -69.365114) (xy 101.284024 -69.365114)
				)
			)
		)
	)
)
